(kicad_pcb
	(version 20260206)
	(generator "pcbnew")
	(generator_version "10.0")
	(general
		(thickness 1.6)
		(legacy_teardrops no)
	)
	(paper "A4")
	(title_block
		(title "panther-plus-userver — 13130-1b_20150205.brd")
		(comment 1 "Honey Badger (Wiwynn) / footprint 624 of 1509 (DIMM4), pads 107-113 of 210")
	)
	(layers
		(0 "F.Cu" signal "TOP")
		(4 "In1.Cu" signal "L2")
		(6 "In2.Cu" signal "L3")
		(8 "In3.Cu" signal "L4")
		(10 "In4.Cu" signal "L5")
		(12 "In5.Cu" signal "L6")
		(14 "In6.Cu" signal "L7")
		(16 "In7.Cu" signal "L8")
		(18 "In8.Cu" signal "L9")
		(20 "In9.Cu" signal "L10")
		(22 "In10.Cu" signal "L11")
		(2 "B.Cu" signal "BOTTOM")
		(9 "F.Adhes" user "F.Adhesive")
		(11 "B.Adhes" user "B.Adhesive")
		(13 "F.Paste" user "Package Geometry/Pastemask Top")
		(15 "B.Paste" user "Package Geometry/Pastemask Bottom")
		(5 "F.SilkS" user "Ref Des/Silkscreen Top")
		(7 "B.SilkS" user "Ref Des/Silkscreen Bottom")
		(1 "F.Mask" user "Board Geometry/Soldermask Top")
		(3 "B.Mask" user "Board Geometry/Soldermask Bottom")
		(17 "Dwgs.User" user "User.Drawings")
		(19 "Cmts.User" user "User.Comments")
		(21 "Eco1.User" user "User.Eco1")
		(23 "Eco2.User" user "User.Eco2")
		(25 "Edge.Cuts" user "Board Geometry/Outline")
		(27 "Margin" user)
		(31 "F.CrtYd" user "Package Geometry/Place Bound Top")
		(29 "B.CrtYd" user "Package Geometry/Place Bound Bottom")
		(35 "F.Fab" user "Ref Des/Assembly Top")
		(33 "B.Fab" user "Ref Des/Assembly Bottom")
	)
	(footprint ""
		(layer "F.Cu")
		(at 159.999934 -5.790692)
		(property "Reference" "DIMM4"
			(at 0 0 0)
			(layer "F.SilkS")
			(hide yes)
			(effects
				(font
					(size 1.27 1.27)
				)
			)
		)
		(property "Value" "DDR3-204P-174-COLAY-1-GP"
			(at -40.682164 -17.468088 0)
			(unlocked yes)
			(layer "F.Fab")
			(hide yes)
			(effects
				(font
					(size 1.016 1.016)
					(thickness 0.1524)
				)
			)
		)
		(property "Device Type" "AS0A626-H8SN-7H-COLAY-1"
			(at -40.682164 -18.992088 0)
			(unlocked yes)
			(layer "F.Fab")
			(hide yes)
			(effects
				(font
					(size 1.016 1.016)
					(thickness 0.1524)
				)
			)
		)
		(duplicate_pad_numbers_are_jumpers no)
		(pad "105" smd custom
			(at 1.949958 4.106672)
			(size 0.1143 0.1143)
			(layers "F.Cu" "F.Mask" "F.Paste")
			(net "M_B_MA1")
			(options
				(clearance outline)
				(anchor circle)
			)
			(primitives
				(gr_poly
					(pts
						(xy 0 0.9017) (xy -0.03175 0.89916) (xy -0.0635 0.889) (xy -0.09144 0.87376) (xy -0.11684 0.85344)
						(xy -0.13716 0.82804) (xy -0.1524 0.8001) (xy -0.16256 0.76835) (xy -0.1651 0.7366) (xy -0.1651 -0.13462)
						(xy -0.17272 -0.14224) (xy -0.19812 -0.1778) (xy -0.2032 -0.18796) (xy -0.20701 -0.19685) (xy -0.21209 -0.20701)
						(xy -0.2159 -0.21717) (xy -0.21844 -0.22733) (xy -0.22225 -0.23876) (xy -0.22352 -0.24892) (xy -0.22606 -0.25908)
						(xy -0.22733 -0.27051) (xy -0.22733 -0.28067) (xy -0.2286 -0.2921) (xy -0.22733 -0.30353) (xy -0.22733 -0.31369)
						(xy -0.22606 -0.32512) (xy -0.22352 -0.33528) (xy -0.22225 -0.34544) (xy -0.21844 -0.35687) (xy -0.2159 -0.36703)
						(xy -0.21209 -0.37719) (xy -0.20701 -0.38735) (xy -0.2032 -0.39624) (xy -0.19812 -0.4064) (xy -0.17272 -0.44196)
						(xy -0.1651 -0.44958) (xy -0.1651 -0.7366) (xy -0.16256 -0.76835) (xy -0.1524 -0.8001) (xy -0.13716 -0.82804)
						(xy -0.11684 -0.85344) (xy -0.09144 -0.87376) (xy -0.0635 -0.889) (xy -0.03175 -0.89916) (xy 0 -0.9017)
						(xy 0.03175 -0.89916) (xy 0.0635 -0.889) (xy 0.09144 -0.87376) (xy 0.11684 -0.85344) (xy 0.13716 -0.82804)
						(xy 0.1524 -0.8001) (xy 0.16256 -0.76835) (xy 0.1651 -0.7366) (xy 0.1651 -0.44958) (xy 0.17272 -0.44196)
						(xy 0.19812 -0.4064) (xy 0.2032 -0.39624) (xy 0.20701 -0.38735) (xy 0.21209 -0.37719) (xy 0.2159 -0.36703)
						(xy 0.21844 -0.35687) (xy 0.22225 -0.34544) (xy 0.22352 -0.33528) (xy 0.22606 -0.32512) (xy 0.22733 -0.31369)
						(xy 0.22733 -0.30353) (xy 0.2286 -0.2921) (xy 0.22733 -0.28067) (xy 0.22733 -0.27051) (xy 0.22606 -0.25908)
						(xy 0.22352 -0.24892) (xy 0.22225 -0.23876) (xy 0.21844 -0.22733) (xy 0.2159 -0.21717) (xy 0.21209 -0.20701)
						(xy 0.20701 -0.19685) (xy 0.2032 -0.18796) (xy 0.19812 -0.1778) (xy 0.17272 -0.14224) (xy 0.1651 -0.13462)
						(xy 0.1651 0.7366) (xy 0.16256 0.76835) (xy 0.1524 0.8001) (xy 0.13716 0.82804) (xy 0.11684 0.85344)
						(xy 0.09144 0.87376) (xy 0.0635 0.889) (xy 0.03175 0.89916)
					)
					(width 0)
					(fill yes)
				)
			)
		)
		(pad "106" smd custom
			(at 2.249932 -4.106672)
			(size 0.1143 0.1143)
			(layers "F.Cu" "F.Mask" "F.Paste")
			(net "M_B_MA2")
			(options
				(clearance outline)
				(anchor circle)
			)
			(primitives
				(gr_poly
					(pts
						(xy 0 0.9017) (xy -0.03175 0.89916) (xy -0.0635 0.889) (xy -0.09144 0.87376) (xy -0.11684 0.85344)
						(xy -0.13716 0.82804) (xy -0.1524 0.8001) (xy -0.16256 0.76835) (xy -0.1651 0.7366) (xy -0.1651 0.44958)
						(xy -0.17272 0.44196) (xy -0.19812 0.4064) (xy -0.2032 0.39624) (xy -0.20701 0.38735) (xy -0.21209 0.37719)
						(xy -0.2159 0.36703) (xy -0.21844 0.35687) (xy -0.22225 0.34544) (xy -0.22352 0.33528) (xy -0.22606 0.32512)
						(xy -0.22733 0.31369) (xy -0.22733 0.30353) (xy -0.2286 0.2921) (xy -0.22733 0.28067) (xy -0.22733 0.27051)
						(xy -0.22606 0.25908) (xy -0.22352 0.24892) (xy -0.22225 0.23876) (xy -0.21844 0.22733) (xy -0.2159 0.21717)
						(xy -0.21209 0.20701) (xy -0.20701 0.19685) (xy -0.2032 0.18796) (xy -0.19812 0.1778) (xy -0.17272 0.14224)
						(xy -0.1651 0.13462) (xy -0.1651 -0.7366) (xy -0.16256 -0.76835) (xy -0.1524 -0.8001) (xy -0.13716 -0.82804)
						(xy -0.11684 -0.85344) (xy -0.09144 -0.87376) (xy -0.0635 -0.889) (xy -0.03175 -0.89916) (xy 0 -0.9017)
						(xy 0.03175 -0.89916) (xy 0.0635 -0.889) (xy 0.09144 -0.87376) (xy 0.11684 -0.85344) (xy 0.13716 -0.82804)
						(xy 0.1524 -0.8001) (xy 0.16256 -0.76835) (xy 0.1651 -0.7366) (xy 0.1651 0.13462) (xy 0.17272 0.14224)
						(xy 0.19812 0.1778) (xy 0.2032 0.18796) (xy 0.20701 0.19685) (xy 0.21209 0.20701) (xy 0.2159 0.21717)
						(xy 0.21844 0.22733) (xy 0.22225 0.23876) (xy 0.22352 0.24892) (xy 0.22606 0.25908) (xy 0.22733 0.27051)
						(xy 0.22733 0.28067) (xy 0.2286 0.2921) (xy 0.22733 0.30353) (xy 0.22733 0.31369) (xy 0.22606 0.32512)
						(xy 0.22352 0.33528) (xy 0.22225 0.34544) (xy 0.21844 0.35687) (xy 0.2159 0.36703) (xy 0.21209 0.37719)
						(xy 0.20701 0.38735) (xy 0.2032 0.39624) (xy 0.19812 0.4064) (xy 0.17272 0.44196) (xy 0.1651 0.44958)
						(xy 0.1651 0.7366) (xy 0.16256 0.76835) (xy 0.1524 0.8001) (xy 0.13716 0.82804) (xy 0.11684 0.85344)
						(xy 0.09144 0.87376) (xy 0.0635 0.889) (xy 0.03175 0.89916)
					)
					(width 0)
					(fill yes)
				)
			)
		)
		(pad "107" smd custom
			(at 2.549906 4.106672)
			(size 0.1143 0.1143)
			(layers "F.Cu" "F.Mask" "F.Paste")
			(net "M_B_MA0")
			(options
				(clearance outline)
				(anchor circle)
			)
			(primitives
				(gr_poly
					(pts
						(xy 0 0.9017) (xy -0.03175 0.89916) (xy -0.0635 0.889) (xy -0.09144 0.87376) (xy -0.11684 0.85344)
						(xy -0.13716 0.82804) (xy -0.1524 0.8001) (xy -0.16256 0.76835) (xy -0.1651 0.7366) (xy -0.1651 0.11938)
						(xy -0.17272 0.11176) (xy -0.19812 0.0762) (xy -0.2032 0.06604) (xy -0.20701 0.05715) (xy -0.21209 0.04699)
						(xy -0.2159 0.03683) (xy -0.21844 0.02667) (xy -0.22225 0.01524) (xy -0.22352 0.00508) (xy -0.22606 -0.00508)
						(xy -0.22733 -0.01651) (xy -0.22733 -0.02667) (xy -0.2286 -0.0381) (xy -0.22733 -0.04953) (xy -0.22733 -0.05969)
						(xy -0.22606 -0.07112) (xy -0.22352 -0.08128) (xy -0.22225 -0.09144) (xy -0.21844 -0.10287) (xy -0.2159 -0.11303)
						(xy -0.21209 -0.12319) (xy -0.20701 -0.13335) (xy -0.2032 -0.14224) (xy -0.19812 -0.1524) (xy -0.17272 -0.18796)
						(xy -0.1651 -0.19558) (xy -0.1651 -0.7366) (xy -0.16256 -0.76835) (xy -0.1524 -0.8001) (xy -0.13716 -0.82804)
						(xy -0.11684 -0.85344) (xy -0.09144 -0.87376) (xy -0.0635 -0.889) (xy -0.03175 -0.89916) (xy 0 -0.9017)
						(xy 0.03175 -0.89916) (xy 0.0635 -0.889) (xy 0.09144 -0.87376) (xy 0.11684 -0.85344) (xy 0.13716 -0.82804)
						(xy 0.1524 -0.8001) (xy 0.16256 -0.76835) (xy 0.1651 -0.7366) (xy 0.1651 -0.19685) (xy 0.17272 -0.18923)
						(xy 0.17907 -0.18034) (xy 0.18669 -0.17145) (xy 0.19177 -0.16256) (xy 0.19812 -0.15367) (xy 0.20828 -0.13335)
						(xy 0.21971 -0.10287) (xy 0.22225 -0.09271) (xy 0.22479 -0.08128) (xy 0.22606 -0.07112) (xy 0.2286 -0.05969)
						(xy 0.2286 -0.01651) (xy 0.22606 -0.00508) (xy 0.22479 0.00508) (xy 0.22225 0.01651) (xy 0.21971 0.02667)
						(xy 0.20828 0.05715) (xy 0.19812 0.07747) (xy 0.19177 0.08636) (xy 0.18669 0.09525) (xy 0.17907 0.10414)
						(xy 0.17272 0.11303) (xy 0.1651 0.12065) (xy 0.1651 0.7366) (xy 0.16256 0.76835) (xy 0.1524 0.8001)
						(xy 0.13716 0.82804) (xy 0.11684 0.85344) (xy 0.09144 0.87376) (xy 0.0635 0.889) (xy 0.03175 0.89916)
					)
					(width 0)
					(fill yes)
				)
			)
		)
		(pad "108" smd custom
			(at 2.84988 -4.106672)
			(size 0.1143 0.1143)
			(layers "F.Cu" "F.Mask" "F.Paste")
			(net "M_B_BS1")
			(options
				(clearance outline)
				(anchor circle)
			)
			(primitives
				(gr_poly
					(pts
						(xy 0 0.9017) (xy -0.03175 0.89916) (xy -0.0635 0.889) (xy -0.09144 0.87376) (xy -0.11684 0.85344)
						(xy -0.13716 0.82804) (xy -0.1524 0.8001) (xy -0.16256 0.76835) (xy -0.1651 0.7366) (xy -0.1651 0.19685)
						(xy -0.17272 0.18923) (xy -0.17907 0.18034) (xy -0.18669 0.17145) (xy -0.19177 0.16256) (xy -0.19812 0.15367)
						(xy -0.20828 0.13335) (xy -0.21971 0.10287) (xy -0.22225 0.09271) (xy -0.22479 0.08128) (xy -0.22606 0.07112)
						(xy -0.2286 0.05969) (xy -0.2286 0.01651) (xy -0.22606 0.00508) (xy -0.22479 -0.00508) (xy -0.22225 -0.01651)
						(xy -0.21971 -0.02667) (xy -0.20828 -0.05715) (xy -0.19812 -0.07747) (xy -0.19177 -0.08636) (xy -0.18669 -0.09525)
						(xy -0.17907 -0.10414) (xy -0.17272 -0.11303) (xy -0.1651 -0.12065) (xy -0.1651 -0.7366) (xy -0.16256 -0.76835)
						(xy -0.1524 -0.8001) (xy -0.13716 -0.82804) (xy -0.11684 -0.85344) (xy -0.09144 -0.87376) (xy -0.0635 -0.889)
						(xy -0.03175 -0.89916) (xy 0 -0.9017) (xy 0.03175 -0.89916) (xy 0.0635 -0.889) (xy 0.09144 -0.87376)
						(xy 0.11684 -0.85344) (xy 0.13716 -0.82804) (xy 0.1524 -0.8001) (xy 0.16256 -0.76835) (xy 0.1651 -0.7366)
						(xy 0.1651 -0.11938) (xy 0.17272 -0.11176) (xy 0.19812 -0.0762) (xy 0.2032 -0.06604) (xy 0.20701 -0.05715)
						(xy 0.21209 -0.04699) (xy 0.2159 -0.03683) (xy 0.21844 -0.02667) (xy 0.22225 -0.01524) (xy 0.22352 -0.00508)
						(xy 0.22606 0.00508) (xy 0.22733 0.01651) (xy 0.22733 0.02667) (xy 0.2286 0.0381) (xy 0.22733 0.04953)
						(xy 0.22733 0.05969) (xy 0.22606 0.07112) (xy 0.22352 0.08128) (xy 0.22225 0.09144) (xy 0.21844 0.10287)
						(xy 0.2159 0.11303) (xy 0.21209 0.12319) (xy 0.20701 0.13335) (xy 0.2032 0.14224) (xy 0.19812 0.1524)
						(xy 0.17272 0.18796) (xy 0.1651 0.19558) (xy 0.1651 0.7366) (xy 0.16256 0.76835) (xy 0.1524 0.8001)
						(xy 0.13716 0.82804) (xy 0.11684 0.85344) (xy 0.09144 0.87376) (xy 0.0635 0.889) (xy 0.03175 0.89916)
					)
					(width 0)
					(fill yes)
				)
			)
		)
		(pad "109" smd custom
			(at 3.150108 4.106672)
			(size 0.1143 0.1143)
			(layers "F.Cu" "F.Mask" "F.Paste")
			(net "PV_VDDR")
			(options
				(clearance outline)
				(anchor circle)
			)
			(primitives
				(gr_poly
					(pts
						(xy 0 0.9017) (xy -0.03175 0.89916) (xy -0.0635 0.889) (xy -0.09144 0.87376) (xy -0.11684 0.85344)
						(xy -0.13716 0.82804) (xy -0.1524 0.8001) (xy -0.16256 0.76835) (xy -0.1651 0.7366) (xy -0.1651 -0.13462)
						(xy -0.17272 -0.14224) (xy -0.19812 -0.1778) (xy -0.2032 -0.18796) (xy -0.20701 -0.19685) (xy -0.21209 -0.20701)
						(xy -0.2159 -0.21717) (xy -0.21844 -0.22733) (xy -0.22225 -0.23876) (xy -0.22352 -0.24892) (xy -0.22606 -0.25908)
						(xy -0.22733 -0.27051) (xy -0.22733 -0.28067) (xy -0.2286 -0.2921) (xy -0.22733 -0.30353) (xy -0.22733 -0.31369)
						(xy -0.22606 -0.32512) (xy -0.22352 -0.33528) (xy -0.22225 -0.34544) (xy -0.21844 -0.35687) (xy -0.2159 -0.36703)
						(xy -0.21209 -0.37719) (xy -0.20701 -0.38735) (xy -0.2032 -0.39624) (xy -0.19812 -0.4064) (xy -0.17272 -0.44196)
						(xy -0.1651 -0.44958) (xy -0.1651 -0.7366) (xy -0.16256 -0.76835) (xy -0.1524 -0.8001) (xy -0.13716 -0.82804)
						(xy -0.11684 -0.85344) (xy -0.09144 -0.87376) (xy -0.0635 -0.889) (xy -0.03175 -0.89916) (xy 0 -0.9017)
						(xy 0.03175 -0.89916) (xy 0.0635 -0.889) (xy 0.09144 -0.87376) (xy 0.11684 -0.85344) (xy 0.13716 -0.82804)
						(xy 0.1524 -0.8001) (xy 0.16256 -0.76835) (xy 0.1651 -0.7366) (xy 0.1651 -0.44958) (xy 0.17272 -0.44196)
						(xy 0.19812 -0.4064) (xy 0.2032 -0.39624) (xy 0.20701 -0.38735) (xy 0.21209 -0.37719) (xy 0.2159 -0.36703)
						(xy 0.21844 -0.35687) (xy 0.22225 -0.34544) (xy 0.22352 -0.33528) (xy 0.22606 -0.32512) (xy 0.22733 -0.31369)
						(xy 0.22733 -0.30353) (xy 0.2286 -0.2921) (xy 0.22733 -0.28067) (xy 0.22733 -0.27051) (xy 0.22606 -0.25908)
						(xy 0.22352 -0.24892) (xy 0.22225 -0.23876) (xy 0.21844 -0.22733) (xy 0.2159 -0.21717) (xy 0.21209 -0.20701)
						(xy 0.20701 -0.19685) (xy 0.2032 -0.18796) (xy 0.19812 -0.1778) (xy 0.17272 -0.14224) (xy 0.1651 -0.13462)
						(xy 0.1651 0.7366) (xy 0.16256 0.76835) (xy 0.1524 0.8001) (xy 0.13716 0.82804) (xy 0.11684 0.85344)
						(xy 0.09144 0.87376) (xy 0.0635 0.889) (xy 0.03175 0.89916)
					)
					(width 0)
					(fill yes)
				)
			)
		)
		(pad "110" smd custom
			(at 3.450082 -4.106672)
			(size 0.1143 0.1143)
			(layers "F.Cu" "F.Mask" "F.Paste")
			(net "PV_VDDR")
			(options
				(clearance outline)
				(anchor circle)
			)
			(primitives
				(gr_poly
					(pts
						(xy 0 0.9017) (xy -0.03175 0.89916) (xy -0.0635 0.889) (xy -0.09144 0.87376) (xy -0.11684 0.85344)
						(xy -0.13716 0.82804) (xy -0.1524 0.8001) (xy -0.16256 0.76835) (xy -0.1651 0.7366) (xy -0.1651 0.44958)
						(xy -0.17272 0.44196) (xy -0.19812 0.4064) (xy -0.2032 0.39624) (xy -0.20701 0.38735) (xy -0.21209 0.37719)
						(xy -0.2159 0.36703) (xy -0.21844 0.35687) (xy -0.22225 0.34544) (xy -0.22352 0.33528) (xy -0.22606 0.32512)
						(xy -0.22733 0.31369) (xy -0.22733 0.30353) (xy -0.2286 0.2921) (xy -0.22733 0.28067) (xy -0.22733 0.27051)
						(xy -0.22606 0.25908) (xy -0.22352 0.24892) (xy -0.22225 0.23876) (xy -0.21844 0.22733) (xy -0.2159 0.21717)
						(xy -0.21209 0.20701) (xy -0.20701 0.19685) (xy -0.2032 0.18796) (xy -0.19812 0.1778) (xy -0.17272 0.14224)
						(xy -0.1651 0.13462) (xy -0.1651 -0.7366) (xy -0.16256 -0.76835) (xy -0.1524 -0.8001) (xy -0.13716 -0.82804)
						(xy -0.11684 -0.85344) (xy -0.09144 -0.87376) (xy -0.0635 -0.889) (xy -0.03175 -0.89916) (xy 0 -0.9017)
						(xy 0.03175 -0.89916) (xy 0.0635 -0.889) (xy 0.09144 -0.87376) (xy 0.11684 -0.85344) (xy 0.13716 -0.82804)
						(xy 0.1524 -0.8001) (xy 0.16256 -0.76835) (xy 0.1651 -0.7366) (xy 0.1651 0.13462) (xy 0.17272 0.14224)
						(xy 0.19812 0.1778) (xy 0.2032 0.18796) (xy 0.20701 0.19685) (xy 0.21209 0.20701) (xy 0.2159 0.21717)
						(xy 0.21844 0.22733) (xy 0.22225 0.23876) (xy 0.22352 0.24892) (xy 0.22606 0.25908) (xy 0.22733 0.27051)
						(xy 0.22733 0.28067) (xy 0.2286 0.2921) (xy 0.22733 0.30353) (xy 0.22733 0.31369) (xy 0.22606 0.32512)
						(xy 0.22352 0.33528) (xy 0.22225 0.34544) (xy 0.21844 0.35687) (xy 0.2159 0.36703) (xy 0.21209 0.37719)
						(xy 0.20701 0.38735) (xy 0.2032 0.39624) (xy 0.19812 0.4064) (xy 0.17272 0.44196) (xy 0.1651 0.44958)
						(xy 0.1651 0.7366) (xy 0.16256 0.76835) (xy 0.1524 0.8001) (xy 0.13716 0.82804) (xy 0.11684 0.85344)
						(xy 0.09144 0.87376) (xy 0.0635 0.889) (xy 0.03175 0.89916)
					)
					(width 0)
					(fill yes)
				)
			)
		)
		(pad "111" smd custom
			(at 3.750056 4.106672)
			(size 0.1143 0.1143)
			(layers "F.Cu" "F.Mask" "F.Paste")
			(net "M_B_CK_DP2")
			(options
				(clearance outline)
				(anchor circle)
			)
			(primitives
				(gr_poly
					(pts
						(xy 0 0.9017) (xy -0.03175 0.89916) (xy -0.0635 0.889) (xy -0.09144 0.87376) (xy -0.11684 0.85344)
						(xy -0.13716 0.82804) (xy -0.1524 0.8001) (xy -0.16256 0.76835) (xy -0.1651 0.7366) (xy -0.1651 0.11938)
						(xy -0.17272 0.11176) (xy -0.19812 0.0762) (xy -0.2032 0.06604) (xy -0.20701 0.05715) (xy -0.21209 0.04699)
						(xy -0.2159 0.03683) (xy -0.21844 0.02667) (xy -0.22225 0.01524) (xy -0.22352 0.00508) (xy -0.22606 -0.00508)
						(xy -0.22733 -0.01651) (xy -0.22733 -0.02667) (xy -0.2286 -0.0381) (xy -0.22733 -0.04953) (xy -0.22733 -0.05969)
						(xy -0.22606 -0.07112) (xy -0.22352 -0.08128) (xy -0.22225 -0.09144) (xy -0.21844 -0.10287) (xy -0.2159 -0.11303)
						(xy -0.21209 -0.12319) (xy -0.20701 -0.13335) (xy -0.2032 -0.14224) (xy -0.19812 -0.1524) (xy -0.17272 -0.18796)
						(xy -0.1651 -0.19558) (xy -0.1651 -0.7366) (xy -0.16256 -0.76835) (xy -0.1524 -0.8001) (xy -0.13716 -0.82804)
						(xy -0.11684 -0.85344) (xy -0.09144 -0.87376) (xy -0.0635 -0.889) (xy -0.03175 -0.89916) (xy 0 -0.9017)
						(xy 0.03175 -0.89916) (xy 0.0635 -0.889) (xy 0.09144 -0.87376) (xy 0.11684 -0.85344) (xy 0.13716 -0.82804)
						(xy 0.1524 -0.8001) (xy 0.16256 -0.76835) (xy 0.1651 -0.7366) (xy 0.1651 -0.19685) (xy 0.17272 -0.18923)
						(xy 0.17907 -0.18034) (xy 0.18669 -0.17145) (xy 0.19177 -0.16256) (xy 0.19812 -0.15367) (xy 0.20828 -0.13335)
						(xy 0.21971 -0.10287) (xy 0.22225 -0.09271) (xy 0.22479 -0.08128) (xy 0.22606 -0.07112) (xy 0.2286 -0.05969)
						(xy 0.2286 -0.01651) (xy 0.22606 -0.00508) (xy 0.22479 0.00508) (xy 0.22225 0.01651) (xy 0.21971 0.02667)
						(xy 0.20828 0.05715) (xy 0.19812 0.07747) (xy 0.19177 0.08636) (xy 0.18669 0.09525) (xy 0.17907 0.10414)
						(xy 0.17272 0.11303) (xy 0.1651 0.12065) (xy 0.1651 0.7366) (xy 0.16256 0.76835) (xy 0.1524 0.8001)
						(xy 0.13716 0.82804) (xy 0.11684 0.85344) (xy 0.09144 0.87376) (xy 0.0635 0.889) (xy 0.03175 0.89916)
					)
					(width 0)
					(fill yes)
				)
			)
		)
	)
)
